(kicad_pcb
	(version 20260206)
	(generator "pcbnew")
	(generator_version "10.0")
	(general
		(thickness 1.6)
		(legacy_teardrops no)
	)
	(paper "A4")
	(title_block
		(title "04192023_DAF0TMB3IC0_F0TG_MB_C_brd_V02_OCP.brd")
		(comment 1 "Grand Teton / footprints 8276-8280 of 8354")
	)
	(layers
		(0 "F.Cu" signal "TOP")
		(4 "In1.Cu" signal "GND")
		(6 "In2.Cu" signal "IN1")
		(8 "In3.Cu" signal "GND1")
		(10 "In4.Cu" signal "IN2")
		(12 "In5.Cu" signal "GND2")
		(14 "In6.Cu" signal "IN3")
		(16 "In7.Cu" signal "GND3")
		(18 "In8.Cu" signal "VCC")
		(20 "In9.Cu" signal "VCC1")
		(22 "In10.Cu" signal "GND4")
		(24 "In11.Cu" signal "IN4")
		(26 "In12.Cu" signal "GND5")
		(28 "In13.Cu" signal "IN5")
		(30 "In14.Cu" signal "GND6")
		(32 "In15.Cu" signal "IN6")
		(34 "In16.Cu" signal "GND7")
		(2 "B.Cu" signal "BOTTOM")
		(9 "F.Adhes" user "F.Adhesive")
		(11 "B.Adhes" user "B.Adhesive")
		(13 "F.Paste" user "Package Geometry/Pastemask Top")
		(15 "B.Paste" user "Package Geometry/Pastemask Bottom")
		(5 "F.SilkS" user "Ref Des/Silkscreen Top")
		(7 "B.SilkS" user "Ref Des/Silkscreen Bottom")
		(1 "F.Mask" user "Board Geometry/Soldermask Top")
		(3 "B.Mask" user "Board Geometry/Soldermask Bottom")
		(17 "Dwgs.User" user "User.Drawings")
		(19 "Cmts.User" user "User.Comments")
		(21 "Eco1.User" user "User.Eco1")
		(23 "Eco2.User" user "User.Eco2")
		(25 "Edge.Cuts" user "Board Geometry/Outline")
		(27 "Margin" user)
		(31 "F.CrtYd" user "Package Geometry/Place Bound Top")
		(29 "B.CrtYd" user "Package Geometry/Place Bound Bottom")
		(35 "F.Fab" user "Ref Des/Assembly Top")
		(33 "B.Fab" user "Ref Des/Assembly Bottom")
	)
	(footprint ""
		(layer "B.Cu")
		(at 212.471508 7.622794 180)
		(property "Reference" "J76"
			(at 4.59867 -1.055878 270)
			(unlocked yes)
			(layer "B.SilkS")
			(effects
				(font
					(size 0.7874 0.5842)
					(thickness 0.1524)
				)
				(justify left mirror)
			)
		)
		(property "Value" ""
			(at 0 0 0)
			(layer "B.Fab")
			(effects
				(font
					(size 1.27 1.27)
				)
				(justify mirror)
			)
		)
		(duplicate_pad_numbers_are_jumpers no)
		(fp_line
			(start 1.2192 2.06756)
			(end 1.2192 -2.06756)
			(stroke
				(width 0.1524)
				(type default)
			)
			(layer "B.SilkS")
		)
		(fp_line
			(start 1.2192 -2.06756)
			(end -1.2192 -2.06756)
			(stroke
				(width 0.1524)
				(type default)
			)
			(layer "B.SilkS")
		)
		(fp_line
			(start -1.2192 2.06756)
			(end 1.2192 2.06756)
			(stroke
				(width 0.1524)
				(type default)
			)
			(layer "B.SilkS")
		)
		(fp_line
			(start -1.2192 -2.06756)
			(end -1.2192 2.06756)
			(stroke
				(width 0.1524)
				(type default)
			)
			(layer "B.SilkS")
		)
		(pad "" np_thru_hole circle
			(at -3.4671 -1.27 90)
			(size 1.0414 1.0414)
			(drill 1.0414)
			(layers "*.Cu" "*.Mask")
			(clearance 0.381)
			(thermal_gap 0.381)
		)
		(pad "" np_thru_hole circle
			(at -3.4671 1.27 90)
			(size 1.0414 1.0414)
			(drill 1.0414)
			(layers "*.Cu" "*.Mask")
			(clearance 0.381)
			(thermal_gap 0.381)
		)
		(pad "" np_thru_hole circle
			(at 2.8829 -1.27 90)
			(size 1.0414 1.0414)
			(drill 1.0414)
			(layers "*.Cu" "*.Mask")
			(clearance 0.381)
			(thermal_gap 0.381)
		)
		(pad "" np_thru_hole circle
			(at 2.8829 1.27 90)
			(size 1.0414 1.0414)
			(drill 1.0414)
			(layers "*.Cu" "*.Mask")
			(clearance 0.381)
			(thermal_gap 0.381)
		)
		(pad "1" smd rect
			(at -0.8255 -0.249936 90)
			(size 0.3048 0.508)
			(layers "B.Cu" "B.Mask" "B.Paste")
			(net "DELTA_L_85_10INCH_BOT_DP")
		)
		(pad "2" smd rect
			(at -0.8255 0.249936 90)
			(size 0.3048 0.508)
			(layers "B.Cu" "B.Mask" "B.Paste")
			(net "DELTA_L_85_10INCH_BOT_DN")
		)
		(pad "3" smd circle
			(at 0 0)
			(size 0 0)
			(layers "B.Cu" "B.Mask" "B.Paste")
			(net "DELTA_L_GND_1")
		)
		(zone
			(layers "F.Cu" "B.Cu" "In1.Cu" "In2.Cu" "In3.Cu" "In4.Cu" "In5.Cu" "In6.Cu"
				"In7.Cu" "In8.Cu" "In9.Cu" "In10.Cu" "In11.Cu" "In12.Cu" "In13.Cu" "In14.Cu"
				"In15.Cu" "In16.Cu"
			)
			(hatch none 0.5)
			(connect_pads
				(clearance 0)
			)
			(min_thickness 0.25)
			(keepout
				(tracks not_allowed)
				(vias allowed)
				(pads allowed)
				(copperpour not_allowed)
				(footprints allowed)
			)
			(placement
				(enabled no)
				(sheetname "")
			)
			(fill
				(thermal_gap 0.5)
				(thermal_bridge_width 0.5)
				(island_removal_mode 0)
			)
			(polygon
				(pts
					(arc
						(start 210.515708 6.352794)
						(mid 208.661508 6.352794)
						(end 210.515708 6.352794)
					)
				)
			)
		)
		(zone
			(layers "F.Cu" "B.Cu" "In1.Cu" "In2.Cu" "In3.Cu" "In4.Cu" "In5.Cu" "In6.Cu"
				"In7.Cu" "In8.Cu" "In9.Cu" "In10.Cu" "In11.Cu" "In12.Cu" "In13.Cu" "In14.Cu"
				"In15.Cu" "In16.Cu"
			)
			(hatch none 0.5)
			(connect_pads
				(clearance 0)
			)
			(min_thickness 0.25)
			(keepout
				(tracks not_allowed)
				(vias allowed)
				(pads allowed)
				(copperpour not_allowed)
				(footprints allowed)
			)
			(placement
				(enabled no)
				(sheetname "")
			)
			(fill
				(thermal_gap 0.5)
				(thermal_bridge_width 0.5)
				(island_removal_mode 0)
			)
			(polygon
				(pts
					(arc
						(start 210.515708 8.892794)
						(mid 208.661508 8.892794)
						(end 210.515708 8.892794)
					)
				)
			)
		)
		(zone
			(layers "F.Cu" "B.Cu" "In1.Cu" "In2.Cu" "In3.Cu" "In4.Cu" "In5.Cu" "In6.Cu"
				"In7.Cu" "In8.Cu" "In9.Cu" "In10.Cu" "In11.Cu" "In12.Cu" "In13.Cu" "In14.Cu"
				"In15.Cu" "In16.Cu"
			)
			(hatch none 0.5)
			(connect_pads
				(clearance 0)
			)
			(min_thickness 0.25)
			(keepout
				(tracks not_allowed)
				(vias allowed)
				(pads allowed)
				(copperpour not_allowed)
				(footprints allowed)
			)
			(placement
				(enabled no)
				(sheetname "")
			)
			(fill
				(thermal_gap 0.5)
				(thermal_bridge_width 0.5)
				(island_removal_mode 0)
			)
			(polygon
				(pts
					(arc
						(start 216.865708 6.352794)
						(mid 215.011508 6.352794)
						(end 216.865708 6.352794)
					)
				)
			)
		)
		(zone
			(layers "F.Cu" "B.Cu" "In1.Cu" "In2.Cu" "In3.Cu" "In4.Cu" "In5.Cu" "In6.Cu"
				"In7.Cu" "In8.Cu" "In9.Cu" "In10.Cu" "In11.Cu" "In12.Cu" "In13.Cu" "In14.Cu"
				"In15.Cu" "In16.Cu"
			)
			(hatch none 0.5)
			(connect_pads
				(clearance 0)
			)
			(min_thickness 0.25)
			(keepout
				(tracks not_allowed)
				(vias allowed)
				(pads allowed)
				(copperpour not_allowed)
				(footprints allowed)
			)
			(placement
				(enabled no)
				(sheetname "")
			)
			(fill
				(thermal_gap 0.5)
				(thermal_bridge_width 0.5)
				(island_removal_mode 0)
			)
			(polygon
				(pts
					(arc
						(start 216.865708 8.892794)
						(mid 215.011508 8.892794)
						(end 216.865708 8.892794)
					)
				)
			)
		)
		(zone
			(layer "B.Cu")
			(hatch none 0.5)
			(connect_pads
				(clearance 0)
			)
			(min_thickness 0.25)
			(keepout
				(tracks not_allowed)
				(vias allowed)
				(pads allowed)
				(copperpour not_allowed)
				(footprints allowed)
			)
			(placement
				(enabled no)
				(sheetname "")
			)
			(fill
				(thermal_gap 0.5)
				(thermal_bridge_width 0.5)
				(island_removal_mode 0)
			)
			(polygon
				(pts
					(xy 213.589108 8.171434) (xy 213.589108 8.07593) (xy 212.992208 8.07593) (xy 212.992208 7.66953)
					(xy 213.589108 7.66953) (xy 213.589108 7.576058) (xy 212.992208 7.576058) (xy 212.992208 7.169658)
					(xy 213.589108 7.169658) (xy 213.589108 7.074154) (xy 212.890608 7.074154) (xy 212.890608 8.171434)
				)
			)
		)
	)
	(footprint ""
		(layer "B.Cu")
		(at 109.895386 -251.781564)
		(property "Reference" "C2459"
			(at 0 0 0)
			(layer "B.SilkS")
			(hide yes)
			(effects
				(font
					(size 1.27 1.27)
				)
				(justify mirror)
			)
		)
		(property "Value" ""
			(at 0 0 0)
			(layer "B.Fab")
			(effects
				(font
					(size 1.27 1.27)
				)
				(justify mirror)
			)
		)
		(duplicate_pad_numbers_are_jumpers no)
		(fp_line
			(start -0.7874 -0.4064)
			(end -0.7874 0.4064)
			(stroke
				(width 0.1524)
				(type default)
			)
			(layer "B.SilkS")
		)
		(fp_line
			(start -0.7874 0.4064)
			(end 0.7874 0.4064)
			(stroke
				(width 0.1524)
				(type default)
			)
			(layer "B.SilkS")
		)
		(fp_line
			(start 0.7874 -0.4064)
			(end -0.7874 -0.4064)
			(stroke
				(width 0.1524)
				(type default)
			)
			(layer "B.SilkS")
		)
		(fp_line
			(start 0.7874 0.4064)
			(end 0.7874 -0.4064)
			(stroke
				(width 0.1524)
				(type default)
			)
			(layer "B.SilkS")
		)
		(fp_line
			(start -0.67945 -0.3048)
			(end -0.67945 0.3048)
			(stroke
				(width 0.1)
				(type default)
			)
			(layer "B.Fab")
		)
		(fp_line
			(start -0.67945 0.3048)
			(end -0.120396 0.3048)
			(stroke
				(width 0.1)
				(type default)
			)
			(layer "B.Fab")
		)
		(fp_line
			(start -0.12065 -0.3048)
			(end -0.67945 -0.3048)
			(stroke
				(width 0.1)
				(type default)
			)
			(layer "B.Fab")
		)
		(fp_line
			(start -0.12065 -0.2794)
			(end -0.12065 -0.3048)
			(stroke
				(width 0.1)
				(type default)
			)
			(layer "B.Fab")
		)
		(fp_line
			(start -0.120396 0.2794)
			(end 0.12065 0.2794)
			(stroke
				(width 0.1)
				(type default)
			)
			(layer "B.Fab")
		)
		(fp_line
			(start -0.120396 0.3048)
			(end -0.120396 0.2794)
			(stroke
				(width 0.1)
				(type default)
			)
			(layer "B.Fab")
		)
		(fp_line
			(start 0.12065 -0.305054)
			(end 0.12065 -0.2794)
			(stroke
				(width 0.1)
				(type default)
			)
			(layer "B.Fab")
		)
		(fp_line
			(start 0.12065 -0.2794)
			(end -0.12065 -0.2794)
			(stroke
				(width 0.1)
				(type default)
			)
			(layer "B.Fab")
		)
		(fp_line
			(start 0.12065 0.2794)
			(end 0.12065 0.3048)
			(stroke
				(width 0.1)
				(type default)
			)
			(layer "B.Fab")
		)
		(fp_line
			(start 0.12065 0.3048)
			(end 0.67945 0.3048)
			(stroke
				(width 0.1)
				(type default)
			)
			(layer "B.Fab")
		)
		(fp_line
			(start 0.67945 -0.305054)
			(end 0.12065 -0.305054)
			(stroke
				(width 0.1)
				(type default)
			)
			(layer "B.Fab")
		)
		(fp_line
			(start 0.67945 0.3048)
			(end 0.67945 -0.305054)
			(stroke
				(width 0.1)
				(type default)
			)
			(layer "B.Fab")
		)
		(pad "1" smd circle
			(at 0.40005 0 180)
			(size 0 0)
			(layers "B.Cu" "B.Mask" "B.Paste")
			(net "PVDDCR_SOC_P1")
		)
		(pad "2" smd circle
			(at -0.40005 0 180)
			(size 0 0)
			(layers "B.Cu" "B.Mask" "B.Paste")
			(net "GND")
		)
	)
	(footprint ""
		(layer "B.Cu")
		(at 108.360464 -257.750564 180)
		(property "Reference" "C2668"
			(at 0 0 0)
			(layer "B.SilkS")
			(hide yes)
			(effects
				(font
					(size 1.27 1.27)
				)
				(justify mirror)
			)
		)
		(property "Value" ""
			(at 0 0 0)
			(layer "B.Fab")
			(effects
				(font
					(size 1.27 1.27)
				)
				(justify mirror)
			)
		)
		(duplicate_pad_numbers_are_jumpers no)
		(fp_line
			(start 0.7874 0.4064)
			(end 0.7874 -0.4064)
			(stroke
				(width 0.1524)
				(type default)
			)
			(layer "B.SilkS")
		)
		(fp_line
			(start 0.7874 -0.4064)
			(end -0.7874 -0.4064)
			(stroke
				(width 0.1524)
				(type default)
			)
			(layer "B.SilkS")
		)
		(fp_line
			(start -0.7874 0.4064)
			(end 0.7874 0.4064)
			(stroke
				(width 0.1524)
				(type default)
			)
			(layer "B.SilkS")
		)
		(fp_line
			(start -0.7874 -0.4064)
			(end -0.7874 0.4064)
			(stroke
				(width 0.1524)
				(type default)
			)
			(layer "B.SilkS")
		)
		(fp_line
			(start 0.67945 0.3048)
			(end 0.67945 -0.305054)
			(stroke
				(width 0.1)
				(type default)
			)
			(layer "B.Fab")
		)
		(fp_line
			(start 0.67945 -0.305054)
			(end 0.12065 -0.305054)
			(stroke
				(width 0.1)
				(type default)
			)
			(layer "B.Fab")
		)
		(fp_line
			(start 0.12065 0.3048)
			(end 0.67945 0.3048)
			(stroke
				(width 0.1)
				(type default)
			)
			(layer "B.Fab")
		)
		(fp_line
			(start 0.12065 0.2794)
			(end 0.12065 0.3048)
			(stroke
				(width 0.1)
				(type default)
			)
			(layer "B.Fab")
		)
		(fp_line
			(start 0.12065 -0.2794)
			(end -0.12065 -0.2794)
			(stroke
				(width 0.1)
				(type default)
			)
			(layer "B.Fab")
		)
		(fp_line
			(start 0.12065 -0.305054)
			(end 0.12065 -0.2794)
			(stroke
				(width 0.1)
				(type default)
			)
			(layer "B.Fab")
		)
		(fp_line
			(start -0.120396 0.3048)
			(end -0.120396 0.2794)
			(stroke
				(width 0.1)
				(type default)
			)
			(layer "B.Fab")
		)
		(fp_line
			(start -0.120396 0.2794)
			(end 0.12065 0.2794)
			(stroke
				(width 0.1)
				(type default)
			)
			(layer "B.Fab")
		)
		(fp_line
			(start -0.12065 -0.2794)
			(end -0.12065 -0.3048)
			(stroke
				(width 0.1)
				(type default)
			)
			(layer "B.Fab")
		)
		(fp_line
			(start -0.12065 -0.3048)
			(end -0.67945 -0.3048)
			(stroke
				(width 0.1)
				(type default)
			)
			(layer "B.Fab")
		)
		(fp_line
			(start -0.67945 0.3048)
			(end -0.120396 0.3048)
			(stroke
				(width 0.1)
				(type default)
			)
			(layer "B.Fab")
		)
		(fp_line
			(start -0.67945 -0.3048)
			(end -0.67945 0.3048)
			(stroke
				(width 0.1)
				(type default)
			)
			(layer "B.Fab")
		)
		(pad "1" smd circle
			(at 0.40005 0)
			(size 0 0)
			(layers "B.Cu" "B.Mask" "B.Paste")
			(net "PVDD18_S5_P1")
		)
		(pad "2" smd circle
			(at -0.40005 0)
			(size 0 0)
			(layers "B.Cu" "B.Mask" "B.Paste")
			(net "GND")
		)
	)
	(footprint ""
		(layer "B.Cu")
		(at 350.318832 -258.830064 180)
		(property "Reference" "C2649"
			(at 0 0 0)
			(layer "B.SilkS")
			(hide yes)
			(effects
				(font
					(size 1.27 1.27)
				)
				(justify mirror)
			)
		)
		(property "Value" ""
			(at 0 0 0)
			(layer "B.Fab")
			(effects
				(font
					(size 1.27 1.27)
				)
				(justify mirror)
			)
		)
		(duplicate_pad_numbers_are_jumpers no)
		(fp_line
			(start 0.7874 0.4064)
			(end 0.7874 -0.4064)
			(stroke
				(width 0.1524)
				(type default)
			)
			(layer "B.SilkS")
		)
		(fp_line
			(start 0.7874 -0.4064)
			(end -0.7874 -0.4064)
			(stroke
				(width 0.1524)
				(type default)
			)
			(layer "B.SilkS")
		)
		(fp_line
			(start -0.7874 0.4064)
			(end 0.7874 0.4064)
			(stroke
				(width 0.1524)
				(type default)
			)
			(layer "B.SilkS")
		)
		(fp_line
			(start -0.7874 -0.4064)
			(end -0.7874 0.4064)
			(stroke
				(width 0.1524)
				(type default)
			)
			(layer "B.SilkS")
		)
		(fp_line
			(start 0.67945 0.3048)
			(end 0.67945 -0.305054)
			(stroke
				(width 0.1)
				(type default)
			)
			(layer "B.Fab")
		)
		(fp_line
			(start 0.67945 -0.305054)
			(end 0.12065 -0.305054)
			(stroke
				(width 0.1)
				(type default)
			)
			(layer "B.Fab")
		)
		(fp_line
			(start 0.12065 0.3048)
			(end 0.67945 0.3048)
			(stroke
				(width 0.1)
				(type default)
			)
			(layer "B.Fab")
		)
		(fp_line
			(start 0.12065 0.2794)
			(end 0.12065 0.3048)
			(stroke
				(width 0.1)
				(type default)
			)
			(layer "B.Fab")
		)
		(fp_line
			(start 0.12065 -0.2794)
			(end -0.12065 -0.2794)
			(stroke
				(width 0.1)
				(type default)
			)
			(layer "B.Fab")
		)
		(fp_line
			(start 0.12065 -0.305054)
			(end 0.12065 -0.2794)
			(stroke
				(width 0.1)
				(type default)
			)
			(layer "B.Fab")
		)
		(fp_line
			(start -0.120396 0.3048)
			(end -0.120396 0.2794)
			(stroke
				(width 0.1)
				(type default)
			)
			(layer "B.Fab")
		)
		(fp_line
			(start -0.120396 0.2794)
			(end 0.12065 0.2794)
			(stroke
				(width 0.1)
				(type default)
			)
			(layer "B.Fab")
		)
		(fp_line
			(start -0.12065 -0.2794)
			(end -0.12065 -0.3048)
			(stroke
				(width 0.1)
				(type default)
			)
			(layer "B.Fab")
		)
		(fp_line
			(start -0.12065 -0.3048)
			(end -0.67945 -0.3048)
			(stroke
				(width 0.1)
				(type default)
			)
			(layer "B.Fab")
		)
		(fp_line
			(start -0.67945 0.3048)
			(end -0.120396 0.3048)
			(stroke
				(width 0.1)
				(type default)
			)
			(layer "B.Fab")
		)
		(fp_line
			(start -0.67945 -0.3048)
			(end -0.67945 0.3048)
			(stroke
				(width 0.1)
				(type default)
			)
			(layer "B.Fab")
		)
		(pad "1" smd circle
			(at 0.40005 0)
			(size 0 0)
			(layers "B.Cu" "B.Mask" "B.Paste")
			(net "PVDDIO_P0")
		)
		(pad "2" smd circle
			(at -0.40005 0)
			(size 0 0)
			(layers "B.Cu" "B.Mask" "B.Paste")
			(net "GND")
		)
	)
	(footprint ""
		(layer "B.Cu")
		(at 375.463562 -416.899344 90)
		(property "Reference" "C6600"
			(at 0 0 90)
			(layer "B.SilkS")
			(hide yes)
			(effects
				(font
					(size 1.27 1.27)
				)
				(justify mirror)
			)
		)
		(property "Value" ""
			(at 0 0 90)
			(layer "B.Fab")
			(effects
				(font
					(size 1.27 1.27)
				)
				(justify mirror)
			)
		)
		(duplicate_pad_numbers_are_jumpers no)
		(fp_line
			(start 0.299974 -0.150114)
			(end -0.299974 -0.150114)
			(stroke
				(width 0.1)
				(type default)
			)
			(layer "B.Fab")
		)
		(fp_line
			(start -0.299974 -0.150114)
			(end -0.299974 0.150114)
			(stroke
				(width 0.1)
				(type default)
			)
			(layer "B.Fab")
		)
		(fp_line
			(start 0.299974 0.150114)
			(end 0.299974 -0.150114)
			(stroke
				(width 0.1)
				(type default)
			)
			(layer "B.Fab")
		)
		(fp_line
			(start -0.299974 0.150114)
			(end 0.299974 0.150114)
			(stroke
				(width 0.1)
				(type default)
			)
			(layer "B.Fab")
		)
		(pad "1" smd rect
			(at 0.2667 0 270)
			(size 0.3048 0.381)
			(layers "B.Cu" "B.Mask" "B.Paste")
			(net "P5E_CPU0_P3_TX_BUF_C_DN<1>")
		)
		(pad "2" smd rect
			(at -0.2667 0 270)
			(size 0.3048 0.381)
			(layers "B.Cu" "B.Mask" "B.Paste")
			(net "P5E_CPU0_P3_TX_BUF_DN<1>")
		)
	)
)
